# BASEBOARD_FAB2 (Tioga Pass) — schematic netlist excerpt (pin names and nets, part order shuffled) for the footprints in the layout excerpt that follows; sources: Cadence DE-HDL packaged netlist, KiCad conversion of Wiwynn_Tioga_Pass_MB.brd

R1U62  RES  0.0 5% EMPTY  pkg 0402  page 152 : A = H_CPU1_MEMKLM_MEMHOT_G_N ; B = H_CPU1_MEMKLM_MEMHOT_G_PCH_N
R3B1  RES  221 1.0% CHIP  pkg 0402  page 55 : A = SVID_ALERT0_CPU1_N ; B = SVID_ALERT0_CPU1_R_N
CT29  CAP  1000PF 50V 10% X7R  pkg 0402LF  page 224 : A = VR_PVDDQ_GHJ_PH1_SW ; B = VR_PVDDQ_GHJ_PH1_SW_RC

(kicad_pcb
	(version 20260206)
	(generator "pcbnew")
	(generator_version "10.0")
	(general
		(thickness 1.6)
		(legacy_teardrops no)
	)
	(paper "A4")
	(title_block
		(title "Wiwynn_Tioga_Pass_MB.brd")
		(comment 1 "Tioga Pass / footprints 1622-1624 of 4770")
	)
	(layers
		(0 "F.Cu" signal "TOP")
		(4 "In1.Cu" signal "L2GND")
		(6 "In2.Cu" signal "L3")
		(8 "In3.Cu" signal "L4GND")
		(10 "In4.Cu" signal "L5")
		(12 "In5.Cu" signal "L6GND")
		(14 "In6.Cu" signal "L7VCC")
		(16 "In7.Cu" signal "L8VCC")
		(18 "In8.Cu" signal "L9GND")
		(20 "In9.Cu" signal "L10")
		(22 "In10.Cu" signal "L11GND")
		(24 "In11.Cu" signal "L12")
		(26 "In12.Cu" signal "L13GND")
		(2 "B.Cu" signal "BOTTOM")
		(9 "F.Adhes" user "F.Adhesive")
		(11 "B.Adhes" user "B.Adhesive")
		(13 "F.Paste" user "Package Geometry/Pastemask Top")
		(15 "B.Paste" user "Package Geometry/Pastemask Bottom")
		(5 "F.SilkS" user "Ref Des/Silkscreen Top")
		(7 "B.SilkS" user "Ref Des/Silkscreen Bottom")
		(1 "F.Mask" user "Board Geometry/Soldermask Top")
		(3 "B.Mask" user "Board Geometry/Soldermask Bottom")
		(17 "Dwgs.User" user "User.Drawings")
		(19 "Cmts.User" user "User.Comments")
		(21 "Eco1.User" user "User.Eco1")
		(23 "Eco2.User" user "User.Eco2")
		(25 "Edge.Cuts" user "Board Geometry/Outline")
		(27 "Margin" user)
		(31 "F.CrtYd" user "Package Geometry/Place Bound Top")
		(29 "B.CrtYd" user "Package Geometry/Place Bound Bottom")
		(35 "F.Fab" user "Ref Des/Assembly Top")
		(33 "B.Fab" user "Ref Des/Assembly Bottom")
	)
	(footprint ""
		(layer "F.Cu")
		(at 437.7055 -16.891 -90)
		(property "Reference" "R1U62"
			(at 0 0 270)
			(layer "F.SilkS")
			(hide yes)
			(effects
				(font
					(size 1.27 1.27)
				)
			)
		)
		(property "Value" ""
			(at 0 0 270)
			(layer "F.Fab")
			(effects
				(font
					(size 1.27 1.27)
				)
			)
		)
		(duplicate_pad_numbers_are_jumpers no)
		(fp_poly
			(pts
				(xy -0.2794 -0.1016) (xy 0.2794 -0.1016) (xy 0.2794 0.9906) (xy -0.2794 0.9906)
			)
			(stroke
				(width 0)
				(type default)
			)
			(fill no)
			(layer "F.CrtYd")
		)
		(fp_line
			(start -0.2794 0.9906)
			(end 0.2794 0.9906)
			(stroke
				(width 0.1)
				(type default)
			)
			(layer "F.Fab")
		)
		(fp_line
			(start 0.2794 0.9906)
			(end 0.2794 -0.1016)
			(stroke
				(width 0.1)
				(type default)
			)
			(layer "F.Fab")
		)
		(fp_line
			(start -0.2794 -0.1016)
			(end -0.2794 0.9906)
			(stroke
				(width 0.1)
				(type default)
			)
			(layer "F.Fab")
		)
		(fp_line
			(start 0.2794 -0.1016)
			(end -0.2794 -0.1016)
			(stroke
				(width 0.1)
				(type default)
			)
			(layer "F.Fab")
		)
		(pad "1" smd rect
			(at 0 0 270)
			(size 0.508 0.508)
			(layers "F.Cu" "F.Mask" "F.Paste")
			(net "H_CPU1_MEMKLM_MEMHOT_G_N")
		)
		(pad "2" smd rect
			(at 0 0.889 270)
			(size 0.508 0.508)
			(layers "F.Cu" "F.Mask" "F.Paste")
			(net "H_CPU1_MEMKLM_MEMHOT_G_PCH_N")
		)
		(zone
			(layer "F.Cu")
			(hatch none 0.5)
			(connect_pads
				(clearance 0)
			)
			(min_thickness 0.25)
			(keepout
				(tracks not_allowed)
				(vias allowed)
				(pads allowed)
				(copperpour not_allowed)
				(footprints allowed)
			)
			(placement
				(enabled no)
				(sheetname "")
			)
			(fill
				(thermal_gap 0.5)
				(thermal_bridge_width 0.5)
				(island_removal_mode 0)
			)
			(polygon
				(pts
					(xy 437.0705 -17.145) (xy 437.0705 -16.637) (xy 437.4515 -16.637) (xy 437.4515 -17.145)
				)
			)
		)
		(zone
			(layer "F.Cu")
			(hatch none 0.5)
			(connect_pads
				(clearance 0)
			)
			(min_thickness 0.25)
			(keepout
				(tracks allowed)
				(vias not_allowed)
				(pads allowed)
				(copperpour not_allowed)
				(footprints allowed)
			)
			(placement
				(enabled no)
				(sheetname "")
			)
			(fill
				(thermal_gap 0.5)
				(thermal_bridge_width 0.5)
				(island_removal_mode 0)
			)
			(polygon
				(pts
					(xy 437.4515 -17.145) (xy 437.4515 -16.637) (xy 437.0705 -16.637) (xy 437.0705 -17.145)
				)
			)
		)
	)
	(footprint ""
		(layer "F.Cu")
		(at 155.583636 -120.080786 90)
		(property "Reference" "R3B1"
			(at 0 0 90)
			(layer "F.SilkS")
			(hide yes)
			(effects
				(font
					(size 1.27 1.27)
				)
			)
		)
		(property "Value" ""
			(at 0 0 90)
			(layer "F.Fab")
			(effects
				(font
					(size 1.27 1.27)
				)
			)
		)
		(duplicate_pad_numbers_are_jumpers no)
		(fp_poly
			(pts
				(xy -0.2794 -0.1016) (xy 0.2794 -0.1016) (xy 0.2794 0.9906) (xy -0.2794 0.9906)
			)
			(stroke
				(width 0)
				(type default)
			)
			(fill no)
			(layer "F.CrtYd")
		)
		(fp_line
			(start 0.2794 -0.1016)
			(end -0.2794 -0.1016)
			(stroke
				(width 0.1)
				(type default)
			)
			(layer "F.Fab")
		)
		(fp_line
			(start -0.2794 -0.1016)
			(end -0.2794 0.9906)
			(stroke
				(width 0.1)
				(type default)
			)
			(layer "F.Fab")
		)
		(fp_line
			(start 0.2794 0.9906)
			(end 0.2794 -0.1016)
			(stroke
				(width 0.1)
				(type default)
			)
			(layer "F.Fab")
		)
		(fp_line
			(start -0.2794 0.9906)
			(end 0.2794 0.9906)
			(stroke
				(width 0.1)
				(type default)
			)
			(layer "F.Fab")
		)
		(pad "1" smd rect
			(at 0 0 90)
			(size 0.508 0.508)
			(layers "F.Cu" "F.Mask" "F.Paste")
			(net "SVID_ALERT0_CPU1_N")
		)
		(pad "2" smd rect
			(at 0 0.889 90)
			(size 0.508 0.508)
			(layers "F.Cu" "F.Mask" "F.Paste")
			(net "SVID_ALERT0_CPU1_R_N")
		)
		(zone
			(layer "F.Cu")
			(hatch none 0.5)
			(connect_pads
				(clearance 0)
			)
			(min_thickness 0.25)
			(keepout
				(tracks allowed)
				(vias not_allowed)
				(pads allowed)
				(copperpour not_allowed)
				(footprints allowed)
			)
			(placement
				(enabled no)
				(sheetname "")
			)
			(fill
				(thermal_gap 0.5)
				(thermal_bridge_width 0.5)
				(island_removal_mode 0)
			)
			(polygon
				(pts
					(xy 155.837636 -119.826786) (xy 155.837636 -120.334786) (xy 156.218636 -120.334786) (xy 156.218636 -119.826786)
				)
			)
		)
		(zone
			(layer "F.Cu")
			(hatch none 0.5)
			(connect_pads
				(clearance 0)
			)
			(min_thickness 0.25)
			(keepout
				(tracks not_allowed)
				(vias allowed)
				(pads allowed)
				(copperpour not_allowed)
				(footprints allowed)
			)
			(placement
				(enabled no)
				(sheetname "")
			)
			(fill
				(thermal_gap 0.5)
				(thermal_bridge_width 0.5)
				(island_removal_mode 0)
			)
			(polygon
				(pts
					(xy 156.218636 -119.826786) (xy 156.218636 -120.334786) (xy 155.837636 -120.334786) (xy 155.837636 -119.826786)
				)
			)
		)
	)
	(footprint ""
		(layer "F.Cu")
		(at 8.787638 -7.129018)
		(property "Reference" "CT29"
			(at -0.8382 -0.67818 0)
			(unlocked yes)
			(layer "F.SilkS")
			(effects
				(font
					(size 0.4064 0.254)
					(thickness 0.1524)
				)
				(justify left)
			)
		)
		(property "Value" ""
			(at 0 0 0)
			(layer "F.Fab")
			(effects
				(font
					(size 1.27 1.27)
				)
			)
		)
		(duplicate_pad_numbers_are_jumpers no)
		(fp_poly
			(pts
				(xy 0.3048 -0.1016) (xy 0.3048 0.9906) (xy -0.3048 0.9906) (xy -0.3048 -0.1016)
			)
			(stroke
				(width 0)
				(type default)
			)
			(fill no)
			(layer "F.CrtYd")
		)
		(fp_line
			(start -0.3048 -0.1016)
			(end -0.3048 0.9906)
			(stroke
				(width 0.1)
				(type default)
			)
			(layer "F.Fab")
		)
		(fp_line
			(start -0.3048 0.9906)
			(end 0.3048 0.9906)
			(stroke
				(width 0.1)
				(type default)
			)
			(layer "F.Fab")
		)
		(fp_line
			(start 0.3048 -0.1016)
			(end -0.3048 -0.1016)
			(stroke
				(width 0.1)
				(type default)
			)
			(layer "F.Fab")
		)
		(fp_line
			(start 0.3048 0.9906)
			(end 0.3048 -0.1016)
			(stroke
				(width 0.1)
				(type default)
			)
			(layer "F.Fab")
		)
		(pad "1" smd rect
			(at 0 0)
			(size 0.508 0.508)
			(layers "F.Cu" "F.Mask" "F.Paste")
			(net "VR_PVDDQ_GHJ_PH1_SW")
		)
		(pad "2" smd rect
			(at 0 0.889)
			(size 0.508 0.508)
			(layers "F.Cu" "F.Mask" "F.Paste")
			(net "VR_PVDDQ_GHJ_PH1_SW_RC")
		)
		(zone
			(layer "F.Cu")
			(hatch none 0.5)
			(connect_pads
				(clearance 0)
			)
			(min_thickness 0.25)
			(keepout
				(tracks allowed)
				(vias not_allowed)
				(pads allowed)
				(copperpour not_allowed)
				(footprints allowed)
			)
			(placement
				(enabled no)
				(sheetname "")
			)
			(fill
				(thermal_gap 0.5)
				(thermal_bridge_width 0.5)
				(island_removal_mode 0)
			)
			(polygon
				(pts
					(xy 8.533638 -6.875018) (xy 9.041638 -6.875018) (xy 9.041638 -6.494018) (xy 8.533638 -6.494018)
				)
			)
		)
		(zone
			(layer "F.Cu")
			(hatch none 0.5)
			(connect_pads
				(clearance 0)
			)
			(min_thickness 0.25)
			(keepout
				(tracks not_allowed)
				(vias allowed)
				(pads allowed)
				(copperpour not_allowed)
				(footprints allowed)
			)
			(placement
				(enabled no)
				(sheetname "")
			)
			(fill
				(thermal_gap 0.5)
				(thermal_bridge_width 0.5)
				(island_removal_mode 0)
			)
			(polygon
				(pts
					(xy 8.533638 -6.494018) (xy 9.041638 -6.494018) (xy 9.041638 -6.875018) (xy 8.533638 -6.875018)
				)
			)
		)
	)
)
